# T6G (Grand Teton) — schematic netlist excerpt (pin names and nets, part order shuffled) for the footprints in the layout excerpt that follows; sources: Cadence DE-HDL packaged netlist, KiCad conversion of 04192023_DAF0TMB3IC0_F0TG_MB_C_brd_V02_OCP.brd

PL7  Q_INDUCTOR4P_14  150NH IND  pkg L_TLM117513Q-151QL_11X7-5XA  page 203
  \1\  = SW_PVDDCR_CPU1_P0_SW6
  \2\  = IND_CPU1_P0_CPL0
  \3\  = IND_CPU1_P0_CPL6
  \4\  = PVDDCR_CPU1_P0

PC198  Q_CAP  470PF 50V 10% X7R  pkg 0402  page 207 : A = PVDD11_S3_P0_TEMP0 ; B = GND

(kicad_pcb
	(version 20260206)
	(generator "pcbnew")
	(generator_version "10.0")
	(general
		(thickness 1.6)
		(legacy_teardrops no)
	)
	(paper "A4")
	(title_block
		(title "04192023_DAF0TMB3IC0_F0TG_MB_C_brd_V02_OCP.brd")
		(comment 1 "Grand Teton / footprints 3847-3848 of 8354")
	)
	(layers
		(0 "F.Cu" signal "TOP")
		(4 "In1.Cu" signal "GND")
		(6 "In2.Cu" signal "IN1")
		(8 "In3.Cu" signal "GND1")
		(10 "In4.Cu" signal "IN2")
		(12 "In5.Cu" signal "GND2")
		(14 "In6.Cu" signal "IN3")
		(16 "In7.Cu" signal "GND3")
		(18 "In8.Cu" signal "VCC")
		(20 "In9.Cu" signal "VCC1")
		(22 "In10.Cu" signal "GND4")
		(24 "In11.Cu" signal "IN4")
		(26 "In12.Cu" signal "GND5")
		(28 "In13.Cu" signal "IN5")
		(30 "In14.Cu" signal "GND6")
		(32 "In15.Cu" signal "IN6")
		(34 "In16.Cu" signal "GND7")
		(2 "B.Cu" signal "BOTTOM")
		(9 "F.Adhes" user "F.Adhesive")
		(11 "B.Adhes" user "B.Adhesive")
		(13 "F.Paste" user "Package Geometry/Pastemask Top")
		(15 "B.Paste" user "Package Geometry/Pastemask Bottom")
		(5 "F.SilkS" user "Ref Des/Silkscreen Top")
		(7 "B.SilkS" user "Ref Des/Silkscreen Bottom")
		(1 "F.Mask" user "Board Geometry/Soldermask Top")
		(3 "B.Mask" user "Board Geometry/Soldermask Bottom")
		(17 "Dwgs.User" user "User.Drawings")
		(19 "Cmts.User" user "User.Comments")
		(21 "Eco1.User" user "User.Eco1")
		(23 "Eco2.User" user "User.Eco2")
		(25 "Edge.Cuts" user "Board Geometry/Outline")
		(27 "Margin" user)
		(31 "F.CrtYd" user "Package Geometry/Place Bound Top")
		(29 "B.CrtYd" user "Package Geometry/Place Bound Bottom")
		(35 "F.Fab" user "Ref Des/Assembly Top")
		(33 "B.Fab" user "Ref Des/Assembly Bottom")
	)
	(footprint ""
		(layer "F.Cu")
		(at 423.627296 -361.818682)
		(property "Reference" "PC198"
			(at 0 0 0)
			(layer "F.SilkS")
			(hide yes)
			(effects
				(font
					(size 1.27 1.27)
				)
			)
		)
		(property "Value" ""
			(at 0 0 0)
			(layer "F.Fab")
			(effects
				(font
					(size 1.27 1.27)
				)
			)
		)
		(duplicate_pad_numbers_are_jumpers no)
		(fp_line
			(start -0.7874 -0.4064)
			(end 0.7874 -0.4064)
			(stroke
				(width 0.1524)
				(type default)
			)
			(layer "F.SilkS")
		)
		(fp_line
			(start -0.7874 0.4064)
			(end -0.7874 -0.4064)
			(stroke
				(width 0.1524)
				(type default)
			)
			(layer "F.SilkS")
		)
		(fp_line
			(start 0.7874 -0.4064)
			(end 0.7874 0.4064)
			(stroke
				(width 0.1524)
				(type default)
			)
			(layer "F.SilkS")
		)
		(fp_line
			(start 0.7874 0.4064)
			(end -0.7874 0.4064)
			(stroke
				(width 0.1524)
				(type default)
			)
			(layer "F.SilkS")
		)
		(fp_line
			(start -0.67945 -0.305054)
			(end -0.12065 -0.305054)
			(stroke
				(width 0.1)
				(type default)
			)
			(layer "F.Fab")
		)
		(fp_line
			(start -0.67945 0.3048)
			(end -0.67945 -0.305054)
			(stroke
				(width 0.1)
				(type default)
			)
			(layer "F.Fab")
		)
		(fp_line
			(start -0.12065 -0.305054)
			(end -0.12065 -0.2794)
			(stroke
				(width 0.1)
				(type default)
			)
			(layer "F.Fab")
		)
		(fp_line
			(start -0.12065 -0.2794)
			(end 0.12065 -0.2794)
			(stroke
				(width 0.1)
				(type default)
			)
			(layer "F.Fab")
		)
		(fp_line
			(start -0.12065 0.2794)
			(end -0.12065 0.3048)
			(stroke
				(width 0.1)
				(type default)
			)
			(layer "F.Fab")
		)
		(fp_line
			(start -0.12065 0.3048)
			(end -0.67945 0.3048)
			(stroke
				(width 0.1)
				(type default)
			)
			(layer "F.Fab")
		)
		(fp_line
			(start 0.120396 0.2794)
			(end -0.12065 0.2794)
			(stroke
				(width 0.1)
				(type default)
			)
			(layer "F.Fab")
		)
		(fp_line
			(start 0.120396 0.3048)
			(end 0.120396 0.2794)
			(stroke
				(width 0.1)
				(type default)
			)
			(layer "F.Fab")
		)
		(fp_line
			(start 0.12065 -0.3048)
			(end 0.67945 -0.3048)
			(stroke
				(width 0.1)
				(type default)
			)
			(layer "F.Fab")
		)
		(fp_line
			(start 0.12065 -0.2794)
			(end 0.12065 -0.3048)
			(stroke
				(width 0.1)
				(type default)
			)
			(layer "F.Fab")
		)
		(fp_line
			(start 0.67945 -0.3048)
			(end 0.67945 0.3048)
			(stroke
				(width 0.1)
				(type default)
			)
			(layer "F.Fab")
		)
		(fp_line
			(start 0.67945 0.3048)
			(end 0.120396 0.3048)
			(stroke
				(width 0.1)
				(type default)
			)
			(layer "F.Fab")
		)
		(pad "1" smd circle
			(at -0.40005 0)
			(size 0 0)
			(layers "F.Cu" "F.Mask" "F.Paste")
			(net "PVDD11_S3_P0_TEMP0")
		)
		(pad "2" smd circle
			(at 0.40005 0)
			(size 0 0)
			(layers "F.Cu" "F.Mask" "F.Paste")
			(net "GND")
		)
	)
	(footprint ""
		(layer "F.Cu")
		(at 351.783904 -330.617322)
		(property "Reference" "PL7"
			(at -1.591056 -16.141446 0)
			(unlocked yes)
			(layer "F.SilkS")
			(effects
				(font
					(size 0.7874 0.5842)
					(thickness 0.1524)
				)
				(justify left)
			)
		)
		(property "Value" ""
			(at 0 0 0)
			(layer "F.Fab")
			(effects
				(font
					(size 1.27 1.27)
				)
			)
		)
		(duplicate_pad_numbers_are_jumpers no)
		(fp_line
			(start -3.750056 -5.500116)
			(end -2.393442 -5.500116)
			(stroke
				(width 0.1524)
				(type default)
			)
			(layer "F.SilkS")
		)
		(fp_line
			(start -3.750056 5.500116)
			(end -3.750056 -5.500116)
			(stroke
				(width 0.1524)
				(type default)
			)
			(layer "F.SilkS")
		)
		(fp_line
			(start -2.393442 5.500116)
			(end -3.750056 5.500116)
			(stroke
				(width 0.1524)
				(type default)
			)
			(layer "F.SilkS")
		)
		(fp_line
			(start 2.393442 5.500116)
			(end 3.750056 5.500116)
			(stroke
				(width 0.1524)
				(type default)
			)
			(layer "F.SilkS")
		)
		(fp_line
			(start 3.750056 -5.500116)
			(end 2.393442 -5.500116)
			(stroke
				(width 0.1524)
				(type default)
			)
			(layer "F.SilkS")
		)
		(fp_line
			(start 3.750056 5.500116)
			(end 3.750056 -5.500116)
			(stroke
				(width 0.1524)
				(type default)
			)
			(layer "F.SilkS")
		)
		(fp_poly
			(pts
				(xy -3.924808 -3.63601) (xy -4.283964 -2.558288) (xy -5.00253 -3.276854)
			)
			(stroke
				(width 0)
				(type default)
			)
			(fill yes)
			(layer "F.SilkS")
		)
		(fp_line
			(start -3.750056 -5.500116)
			(end -3.750056 5.500116)
			(stroke
				(width 0.1)
				(type default)
			)
			(layer "F.Fab")
		)
		(fp_line
			(start -3.750056 5.500116)
			(end 3.750056 5.500116)
			(stroke
				(width 0.1)
				(type default)
			)
			(layer "F.Fab")
		)
		(fp_line
			(start 3.750056 -5.500116)
			(end -3.750056 -5.500116)
			(stroke
				(width 0.1)
				(type default)
			)
			(layer "F.Fab")
		)
		(fp_line
			(start 3.750056 5.500116)
			(end 3.750056 -5.500116)
			(stroke
				(width 0.1)
				(type default)
			)
			(layer "F.Fab")
		)
		(fp_poly
			(pts
				(xy -4.9276 -4.757928) (xy -4.9276 -3.741928) (xy -3.9116 -4.249928)
			)
			(stroke
				(width 0)
				(type default)
			)
			(fill yes)
			(layer "F.Fab")
		)
		(pad "1" smd rect
			(at 0 -4.249928 270)
			(size 2.413 4.5212)
			(layers "F.Cu" "F.Mask" "F.Paste")
			(net "SW_PVDDCR_CPU1_P0_SW6")
		)
		(pad "2" smd rect
			(at 0 -1.175004 270)
			(size 1.3716 4.5212)
			(layers "F.Cu" "F.Mask" "F.Paste")
			(net "IND_CPU1_P0_CPL0")
		)
		(pad "3" smd rect
			(at 0 1.175004 270)
			(size 1.3716 4.5212)
			(layers "F.Cu" "F.Mask" "F.Paste")
			(net "IND_CPU1_P0_CPL6")
		)
		(pad "4" smd rect
			(at 0 4.249928 270)
			(size 2.413 4.5212)
			(layers "F.Cu" "F.Mask" "F.Paste")
			(net "PVDDCR_CPU1_P0")
		)
	)
)
